# S9S_MB_2U (Grand Teton) — schematic netlist excerpt (pin names and nets, part order shuffled) for the footprints in the layout excerpt that follows; sources: Cadence DE-HDL packaged netlist, KiCad conversion of 03242023_DA0F0TMBIJ0_F0T_Motherboard_J_brd_V01_OCP.brd

R4776  Q_RES  17.8K 1% EMPTY  pkg 0402LF  page 307 : A = P12V_AUX ; B = P12V_AUX_UV_TRIGGER
PR4242  Q_RES  0 5% CHIP  pkg 0402LF  page 292 : A = NC_PVCCINFAON_CPU1_ACSP3 ; B = GND

(kicad_pcb
	(version 20260206)
	(generator "pcbnew")
	(generator_version "10.0")
	(general
		(thickness 1.6)
		(legacy_teardrops no)
	)
	(paper "A4")
	(title_block
		(title "03242023_DA0F0TMBIJ0_F0T_Motherboard_J_brd_V01_OCP.brd")
		(comment 1 "Grand Teton / footprints 2774-2775 of 6105")
	)
	(layers
		(0 "F.Cu" signal "TOP")
		(4 "In1.Cu" signal "GND")
		(6 "In2.Cu" signal "IN1")
		(8 "In3.Cu" signal "GND1")
		(10 "In4.Cu" signal "IN2")
		(12 "In5.Cu" signal "GND2")
		(14 "In6.Cu" signal "IN3")
		(16 "In7.Cu" signal "GND3")
		(18 "In8.Cu" signal "VCC")
		(20 "In9.Cu" signal "VCC1")
		(22 "In10.Cu" signal "GND4")
		(24 "In11.Cu" signal "IN4")
		(26 "In12.Cu" signal "GND5")
		(28 "In13.Cu" signal "IN5")
		(30 "In14.Cu" signal "GND6")
		(32 "In15.Cu" signal "IN6")
		(34 "In16.Cu" signal "GND7")
		(2 "B.Cu" signal "BOTTOM")
		(9 "F.Adhes" user "F.Adhesive")
		(11 "B.Adhes" user "B.Adhesive")
		(13 "F.Paste" user "Package Geometry/Pastemask Top")
		(15 "B.Paste" user "Package Geometry/Pastemask Bottom")
		(5 "F.SilkS" user "Ref Des/Silkscreen Top")
		(7 "B.SilkS" user "Ref Des/Silkscreen Bottom")
		(1 "F.Mask" user "Board Geometry/Soldermask Top")
		(3 "B.Mask" user "Board Geometry/Soldermask Bottom")
		(17 "Dwgs.User" user "User.Drawings")
		(19 "Cmts.User" user "User.Comments")
		(21 "Eco1.User" user "User.Eco1")
		(23 "Eco2.User" user "User.Eco2")
		(25 "Edge.Cuts" user "Board Geometry/Outline")
		(27 "Margin" user)
		(31 "F.CrtYd" user "Package Geometry/Place Bound Top")
		(29 "B.CrtYd" user "Package Geometry/Place Bound Bottom")
		(35 "F.Fab" user "Ref Des/Assembly Top")
		(33 "B.Fab" user "Ref Des/Assembly Bottom")
	)
	(footprint ""
		(layer "F.Cu")
		(at 212.4202 -107.4166 90)
		(property "Reference" "R4776"
			(at 0 0 90)
			(layer "F.SilkS")
			(hide yes)
			(effects
				(font
					(size 1.27 1.27)
				)
			)
		)
		(property "Value" ""
			(at 0 0 90)
			(layer "F.Fab")
			(effects
				(font
					(size 1.27 1.27)
				)
			)
		)
		(duplicate_pad_numbers_are_jumpers no)
		(fp_line
			(start 0.7874 -0.4064)
			(end 0.7874 0.4064)
			(stroke
				(width 0.1524)
				(type default)
			)
			(layer "F.SilkS")
		)
		(fp_line
			(start -0.7874 -0.4064)
			(end 0.7874 -0.4064)
			(stroke
				(width 0.1524)
				(type default)
			)
			(layer "F.SilkS")
		)
		(fp_line
			(start 0.7874 0.4064)
			(end -0.7874 0.4064)
			(stroke
				(width 0.1524)
				(type default)
			)
			(layer "F.SilkS")
		)
		(fp_line
			(start -0.7874 0.4064)
			(end -0.7874 -0.4064)
			(stroke
				(width 0.1524)
				(type default)
			)
			(layer "F.SilkS")
		)
		(fp_line
			(start -0.12065 -0.305054)
			(end -0.12065 -0.2794)
			(stroke
				(width 0.1)
				(type default)
			)
			(layer "F.Fab")
		)
		(fp_line
			(start -0.67945 -0.305054)
			(end -0.12065 -0.305054)
			(stroke
				(width 0.1)
				(type default)
			)
			(layer "F.Fab")
		)
		(fp_line
			(start 0.67945 -0.3048)
			(end 0.67945 0.3048)
			(stroke
				(width 0.1)
				(type default)
			)
			(layer "F.Fab")
		)
		(fp_line
			(start 0.12065 -0.3048)
			(end 0.67945 -0.3048)
			(stroke
				(width 0.1)
				(type default)
			)
			(layer "F.Fab")
		)
		(fp_line
			(start 0.12065 -0.2794)
			(end 0.12065 -0.3048)
			(stroke
				(width 0.1)
				(type default)
			)
			(layer "F.Fab")
		)
		(fp_line
			(start -0.12065 -0.2794)
			(end 0.12065 -0.2794)
			(stroke
				(width 0.1)
				(type default)
			)
			(layer "F.Fab")
		)
		(fp_line
			(start 0.120396 0.2794)
			(end -0.12065 0.2794)
			(stroke
				(width 0.1)
				(type default)
			)
			(layer "F.Fab")
		)
		(fp_line
			(start -0.12065 0.2794)
			(end -0.12065 0.3048)
			(stroke
				(width 0.1)
				(type default)
			)
			(layer "F.Fab")
		)
		(fp_line
			(start 0.67945 0.3048)
			(end 0.120396 0.3048)
			(stroke
				(width 0.1)
				(type default)
			)
			(layer "F.Fab")
		)
		(fp_line
			(start 0.120396 0.3048)
			(end 0.120396 0.2794)
			(stroke
				(width 0.1)
				(type default)
			)
			(layer "F.Fab")
		)
		(fp_line
			(start -0.12065 0.3048)
			(end -0.67945 0.3048)
			(stroke
				(width 0.1)
				(type default)
			)
			(layer "F.Fab")
		)
		(fp_line
			(start -0.67945 0.3048)
			(end -0.67945 -0.305054)
			(stroke
				(width 0.1)
				(type default)
			)
			(layer "F.Fab")
		)
		(pad "1" smd circle
			(at -0.40005 0 90)
			(size 0 0)
			(layers "F.Cu" "F.Mask" "F.Paste")
			(net "P12V_AUX")
		)
		(pad "2" smd circle
			(at 0.40005 0 90)
			(size 0 0)
			(layers "F.Cu" "F.Mask" "F.Paste")
			(net "P12V_AUX_UV_TRIGGER")
		)
	)
	(footprint ""
		(layer "F.Cu")
		(at 32.353758 -138.03757 90)
		(property "Reference" "PR4242"
			(at 0 0 90)
			(layer "F.SilkS")
			(hide yes)
			(effects
				(font
					(size 1.27 1.27)
				)
			)
		)
		(property "Value" ""
			(at 0 0 90)
			(layer "F.Fab")
			(effects
				(font
					(size 1.27 1.27)
				)
			)
		)
		(duplicate_pad_numbers_are_jumpers no)
		(fp_line
			(start 0.7874 -0.4064)
			(end 0.7874 0.4064)
			(stroke
				(width 0.1524)
				(type default)
			)
			(layer "F.SilkS")
		)
		(fp_line
			(start -0.7874 -0.4064)
			(end 0.7874 -0.4064)
			(stroke
				(width 0.1524)
				(type default)
			)
			(layer "F.SilkS")
		)
		(fp_line
			(start 0.7874 0.4064)
			(end -0.7874 0.4064)
			(stroke
				(width 0.1524)
				(type default)
			)
			(layer "F.SilkS")
		)
		(fp_line
			(start -0.7874 0.4064)
			(end -0.7874 -0.4064)
			(stroke
				(width 0.1524)
				(type default)
			)
			(layer "F.SilkS")
		)
		(fp_line
			(start -0.12065 -0.305054)
			(end -0.12065 -0.2794)
			(stroke
				(width 0.1)
				(type default)
			)
			(layer "F.Fab")
		)
		(fp_line
			(start -0.67945 -0.305054)
			(end -0.12065 -0.305054)
			(stroke
				(width 0.1)
				(type default)
			)
			(layer "F.Fab")
		)
		(fp_line
			(start 0.67945 -0.3048)
			(end 0.67945 0.3048)
			(stroke
				(width 0.1)
				(type default)
			)
			(layer "F.Fab")
		)
		(fp_line
			(start 0.12065 -0.3048)
			(end 0.67945 -0.3048)
			(stroke
				(width 0.1)
				(type default)
			)
			(layer "F.Fab")
		)
		(fp_line
			(start 0.12065 -0.2794)
			(end 0.12065 -0.3048)
			(stroke
				(width 0.1)
				(type default)
			)
			(layer "F.Fab")
		)
		(fp_line
			(start -0.12065 -0.2794)
			(end 0.12065 -0.2794)
			(stroke
				(width 0.1)
				(type default)
			)
			(layer "F.Fab")
		)
		(fp_line
			(start 0.120396 0.2794)
			(end -0.12065 0.2794)
			(stroke
				(width 0.1)
				(type default)
			)
			(layer "F.Fab")
		)
		(fp_line
			(start -0.12065 0.2794)
			(end -0.12065 0.3048)
			(stroke
				(width 0.1)
				(type default)
			)
			(layer "F.Fab")
		)
		(fp_line
			(start 0.67945 0.3048)
			(end 0.120396 0.3048)
			(stroke
				(width 0.1)
				(type default)
			)
			(layer "F.Fab")
		)
		(fp_line
			(start 0.120396 0.3048)
			(end 0.120396 0.2794)
			(stroke
				(width 0.1)
				(type default)
			)
			(layer "F.Fab")
		)
		(fp_line
			(start -0.12065 0.3048)
			(end -0.67945 0.3048)
			(stroke
				(width 0.1)
				(type default)
			)
			(layer "F.Fab")
		)
		(fp_line
			(start -0.67945 0.3048)
			(end -0.67945 -0.305054)
			(stroke
				(width 0.1)
				(type default)
			)
			(layer "F.Fab")
		)
		(pad "1" smd circle
			(at -0.40005 0 90)
			(size 0 0)
			(layers "F.Cu" "F.Mask" "F.Paste")
			(net "NC_PVCCINFAON_CPU1_ACSP3")
		)
		(pad "2" smd circle
			(at 0.40005 0 90)
			(size 0 0)
			(layers "F.Cu" "F.Mask" "F.Paste")
			(net "GND")
		)
	)
)
